# TIMECARD (Time Appliance Project (Time Card)) — schematic netlist excerpt (pin names and nets, part order shuffled) for the footprints in the layout excerpt that follows; sources: Cadence DE-HDL packaged netlist, KiCad conversion of R4006-B0001-02_R01.brd

C252  CAPACITOR  0.1UF 10V 10%  pkg SMC_0402R_H022  page 15 : \1\ = OSC_200M_CLKN ; \2\ = MHZ200CLKN_CLKIN
R296  RESISTOR  4.7KOHM 1%  pkg SMC_0402R_H016  page 18 : \1\ = XP3R3V_FPGA ; \2\ = R_SHT3X_RST_N

(kicad_pcb
	(version 20260206)
	(generator "pcbnew")
	(generator_version "10.0")
	(general
		(thickness 1.6)
		(legacy_teardrops no)
	)
	(paper "A4")
	(title_block
		(title "timecard-production-celestica-r4006 — R4006-B0001-02_R01.brd")
		(comment 1 "Time Appliance Project (Time Card) / footprints 89-90 of 1113")
	)
	(layers
		(0 "F.Cu" signal "TOP")
		(4 "In1.Cu" signal "L02_GND1")
		(6 "In2.Cu" signal "L03_SIG1")
		(8 "In3.Cu" signal "L04_GND2")
		(10 "In4.Cu" signal "L05_VCC1")
		(12 "In5.Cu" signal "L06_VCC2")
		(14 "In6.Cu" signal "L07_GND3")
		(16 "In7.Cu" signal "L08_SIG2")
		(18 "In8.Cu" signal "L09_GND4")
		(2 "B.Cu" signal "BOTTOM")
		(9 "F.Adhes" user "F.Adhesive")
		(11 "B.Adhes" user "B.Adhesive")
		(13 "F.Paste" user "Package Geometry/Pastemask Top")
		(15 "B.Paste" user "Package Geometry/Pastemask Bottom")
		(5 "F.SilkS" user "Ref Des/Silkscreen Top")
		(7 "B.SilkS" user "Ref Des/Silkscreen Bottom")
		(1 "F.Mask" user "Board Geometry/Soldermask Top")
		(3 "B.Mask" user "Board Geometry/Soldermask Bottom")
		(17 "Dwgs.User" user "User.Drawings")
		(19 "Cmts.User" user "User.Comments")
		(21 "Eco1.User" user "User.Eco1")
		(23 "Eco2.User" user "User.Eco2")
		(25 "Edge.Cuts" user "Board Geometry/Outline")
		(27 "Margin" user)
		(31 "F.CrtYd" user "Package Geometry/Place Bound Top")
		(29 "B.CrtYd" user "Package Geometry/Place Bound Bottom")
		(35 "F.Fab" user "Ref Des/Assembly Top")
		(33 "B.Fab" user "Ref Des/Assembly Bottom")
	)
	(footprint ""
		(layer "F.Cu")
		(at 150.381462 -56.8706)
		(property "Reference" "R296"
			(at -1.410462 -3.66903 0)
			(unlocked yes)
			(layer "F.SilkS")
			(effects
				(font
					(size 0.7874 0.5842)
					(thickness 0.1524)
				)
			)
		)
		(property "Value" "VAL*"
			(at 0.02032 2.13233 0)
			(unlocked yes)
			(layer "F.Fab")
			(hide yes)
			(effects
				(font
					(size 0.7874 0.5842)
					(thickness 0.1524)
				)
			)
		)
		(property "Tolerance" "TOL*"
			(at 0.044704 3.05435 0)
			(unlocked yes)
			(layer "Cmts.User")
			(hide yes)
			(effects
				(font
					(size 0.7874 0.5842)
					(thickness 0.1524)
				)
			)
		)
		(property "User Part Number" "PARTNUM*"
			(at 0.02032 4.024884 0)
			(unlocked yes)
			(layer "Cmts.User")
			(hide yes)
			(effects
				(font
					(size 0.7874 0.5842)
					(thickness 0.1524)
				)
			)
		)
		(property "Device Type" "RESISTOR-G155-14701-01,4.7KOHMA"
			(at 0.008382 1.210564 0)
			(unlocked yes)
			(layer "F.Fab")
			(hide yes)
			(effects
				(font
					(size 0.7874 0.5842)
					(thickness 0.1524)
				)
			)
		)
		(duplicate_pad_numbers_are_jumpers no)
		(fp_line
			(start -1.143 -0.5588)
			(end -1.143 0.5588)
			(stroke
				(width 0.1)
				(type default)
			)
			(layer "F.SilkS")
		)
		(fp_line
			(start -1.143 0.5588)
			(end 1.143 0.5588)
			(stroke
				(width 0.1)
				(type default)
			)
			(layer "F.SilkS")
		)
		(fp_line
			(start 1.143 -0.5588)
			(end -1.143 -0.5588)
			(stroke
				(width 0.1)
				(type default)
			)
			(layer "F.SilkS")
		)
		(fp_line
			(start 1.143 0.5588)
			(end 1.143 -0.5588)
			(stroke
				(width 0.1)
				(type default)
			)
			(layer "F.SilkS")
		)
		(fp_rect
			(start 1.143 -0.5588)
			(end -1.143 0.5588)
			(stroke
				(width 0)
				(type default)
			)
			(fill no)
			(layer "F.CrtYd")
		)
		(fp_line
			(start -0.508 -0.3048)
			(end -0.508 0.3048)
			(stroke
				(width 0.1)
				(type default)
			)
			(layer "F.Fab")
		)
		(fp_line
			(start -0.508 0.3048)
			(end 0.508 0.3048)
			(stroke
				(width 0.1)
				(type default)
			)
			(layer "F.Fab")
		)
		(fp_line
			(start 0.508 -0.3048)
			(end -0.508 -0.3048)
			(stroke
				(width 0.1)
				(type default)
			)
			(layer "F.Fab")
		)
		(fp_line
			(start 0.508 0.3048)
			(end 0.508 -0.3048)
			(stroke
				(width 0.1)
				(type default)
			)
			(layer "F.Fab")
		)
		(pad "1" smd rect
			(at -0.5334 0)
			(size 0.7112 0.6096)
			(layers "F.Cu" "F.Mask" "F.Paste")
			(net "XP3R3V_FPGA")
		)
		(pad "2" smd rect
			(at 0.5334 0)
			(size 0.7112 0.6096)
			(layers "F.Cu" "F.Mask" "F.Paste")
			(net "R_SHT3X_RST_N")
		)
		(zone
			(layer "F.Cu")
			(hatch none 0.5)
			(connect_pads
				(clearance 0)
			)
			(min_thickness 0.25)
			(keepout
				(tracks allowed)
				(vias not_allowed)
				(pads allowed)
				(copperpour not_allowed)
				(footprints allowed)
			)
			(placement
				(enabled no)
				(sheetname "")
			)
			(fill
				(thermal_gap 0.5)
				(thermal_bridge_width 0.5)
				(island_removal_mode 0)
			)
			(polygon
				(pts
					(xy 150.457662 -57.1754) (xy 150.305262 -57.1754) (xy 150.305262 -56.5658) (xy 150.457662 -56.5658)
				)
			)
		)
	)
	(footprint ""
		(layer "F.Cu")
		(at 110.9726 -26.7208 90)
		(property "Reference" "C252"
			(at -8.5598 -0.31623 90)
			(unlocked yes)
			(layer "F.SilkS")
			(effects
				(font
					(size 0.7874 0.5842)
					(thickness 0.1524)
				)
			)
		)
		(property "Value" "VAL*"
			(at 0.0762 2.067306 90)
			(unlocked yes)
			(layer "F.Fab")
			(hide yes)
			(effects
				(font
					(size 0.7874 0.5842)
					(thickness 0.1524)
				)
			)
		)
		(property "Device Type" "CAPACITOR-G105-0B104-CK,0.1UF,A"
			(at 0.0508 1.127506 90)
			(unlocked yes)
			(layer "F.Fab")
			(hide yes)
			(effects
				(font
					(size 0.7874 0.5842)
					(thickness 0.1524)
				)
			)
		)
		(property "User Part Number" "PARTNUM*"
			(at 0.1016 4.023106 90)
			(unlocked yes)
			(layer "Cmts.User")
			(hide yes)
			(effects
				(font
					(size 0.7874 0.5842)
					(thickness 0.1524)
				)
			)
		)
		(property "Tolerance" "TOL*"
			(at 0.0762 3.032506 90)
			(unlocked yes)
			(layer "Cmts.User")
			(hide yes)
			(effects
				(font
					(size 0.7874 0.5842)
					(thickness 0.1524)
				)
			)
		)
		(duplicate_pad_numbers_are_jumpers no)
		(fp_line
			(start 1.143 -0.5588)
			(end -1.143 -0.5588)
			(stroke
				(width 0.1)
				(type default)
			)
			(layer "F.SilkS")
		)
		(fp_line
			(start -1.143 -0.5588)
			(end -1.143 0.5588)
			(stroke
				(width 0.1)
				(type default)
			)
			(layer "F.SilkS")
		)
		(fp_line
			(start 1.143 0.5588)
			(end 1.143 -0.5588)
			(stroke
				(width 0.1)
				(type default)
			)
			(layer "F.SilkS")
		)
		(fp_line
			(start -1.143 0.5588)
			(end 1.143 0.5588)
			(stroke
				(width 0.1)
				(type default)
			)
			(layer "F.SilkS")
		)
		(fp_rect
			(start 1.143 -0.5588)
			(end -1.143 0.5588)
			(stroke
				(width 0)
				(type default)
			)
			(fill no)
			(layer "F.CrtYd")
		)
		(fp_line
			(start 0.508 -0.3048)
			(end -0.508 -0.3048)
			(stroke
				(width 0.1)
				(type default)
			)
			(layer "F.Fab")
		)
		(fp_line
			(start -0.508 -0.3048)
			(end -0.508 0.3048)
			(stroke
				(width 0.1)
				(type default)
			)
			(layer "F.Fab")
		)
		(fp_line
			(start 0.508 0.3048)
			(end 0.508 -0.3048)
			(stroke
				(width 0.1)
				(type default)
			)
			(layer "F.Fab")
		)
		(fp_line
			(start -0.508 0.3048)
			(end 0.508 0.3048)
			(stroke
				(width 0.1)
				(type default)
			)
			(layer "F.Fab")
		)
		(pad "1" smd rect
			(at -0.5334 0 90)
			(size 0.7112 0.6096)
			(layers "F.Cu" "F.Mask" "F.Paste")
			(net "OSC_200M_CLKN")
		)
		(pad "2" smd rect
			(at 0.5334 0 90)
			(size 0.7112 0.6096)
			(layers "F.Cu" "F.Mask" "F.Paste")
			(net "MHZ200CLKN_CLKIN")
		)
		(zone
			(layer "F.Cu")
			(hatch none 0.5)
			(connect_pads
				(clearance 0)
			)
			(min_thickness 0.25)
			(keepout
				(tracks allowed)
				(vias not_allowed)
				(pads allowed)
				(copperpour not_allowed)
				(footprints allowed)
			)
			(placement
				(enabled no)
				(sheetname "")
			)
			(fill
				(thermal_gap 0.5)
				(thermal_bridge_width 0.5)
				(island_removal_mode 0)
			)
			(polygon
				(pts
					(xy 110.6678 -26.797) (xy 110.6678 -26.6446) (xy 111.2774 -26.6446) (xy 111.2774 -26.797)
				)
			)
		)
	)
)
